(kicad_pcb
	(version 20260206)
	(generator "pcbnew")
	(generator_version "10.0")
	(general
		(thickness 1.6)
		(legacy_teardrops no)
	)
	(paper "A4")
	(title_block
		(title "04192023_DAF0TMB3IC0_F0TG_MB_C_brd_V02_OCP.brd")
		(comment 1 "Grand Teton / footprints 5593-5599 of 8354")
	)
	(layers
		(0 "F.Cu" signal "TOP")
		(4 "In1.Cu" signal "GND")
		(6 "In2.Cu" signal "IN1")
		(8 "In3.Cu" signal "GND1")
		(10 "In4.Cu" signal "IN2")
		(12 "In5.Cu" signal "GND2")
		(14 "In6.Cu" signal "IN3")
		(16 "In7.Cu" signal "GND3")
		(18 "In8.Cu" signal "VCC")
		(20 "In9.Cu" signal "VCC1")
		(22 "In10.Cu" signal "GND4")
		(24 "In11.Cu" signal "IN4")
		(26 "In12.Cu" signal "GND5")
		(28 "In13.Cu" signal "IN5")
		(30 "In14.Cu" signal "GND6")
		(32 "In15.Cu" signal "IN6")
		(34 "In16.Cu" signal "GND7")
		(2 "B.Cu" signal "BOTTOM")
		(9 "F.Adhes" user "F.Adhesive")
		(11 "B.Adhes" user "B.Adhesive")
		(13 "F.Paste" user "Package Geometry/Pastemask Top")
		(15 "B.Paste" user "Package Geometry/Pastemask Bottom")
		(5 "F.SilkS" user "Ref Des/Silkscreen Top")
		(7 "B.SilkS" user "Ref Des/Silkscreen Bottom")
		(1 "F.Mask" user "Board Geometry/Soldermask Top")
		(3 "B.Mask" user "Board Geometry/Soldermask Bottom")
		(17 "Dwgs.User" user "User.Drawings")
		(19 "Cmts.User" user "User.Comments")
		(21 "Eco1.User" user "User.Eco1")
		(23 "Eco2.User" user "User.Eco2")
		(25 "Edge.Cuts" user "Board Geometry/Outline")
		(27 "Margin" user)
		(31 "F.CrtYd" user "Package Geometry/Place Bound Top")
		(29 "B.CrtYd" user "Package Geometry/Place Bound Bottom")
		(35 "F.Fab" user "Ref Des/Assembly Top")
		(33 "B.Fab" user "Ref Des/Assembly Bottom")
	)
	(footprint ""
		(layer "B.Cu")
		(at 197.002908 -113.427256)
		(property "Reference" "R1282"
			(at 0 0 0)
			(layer "B.SilkS")
			(hide yes)
			(effects
				(font
					(size 1.27 1.27)
				)
				(justify mirror)
			)
		)
		(property "Value" ""
			(at 0 0 0)
			(layer "B.Fab")
			(effects
				(font
					(size 1.27 1.27)
				)
				(justify mirror)
			)
		)
		(duplicate_pad_numbers_are_jumpers no)
		(fp_line
			(start -0.7874 -0.4064)
			(end -0.7874 0.4064)
			(stroke
				(width 0.1524)
				(type default)
			)
			(layer "B.SilkS")
		)
		(fp_line
			(start -0.7874 0.4064)
			(end 0.7874 0.4064)
			(stroke
				(width 0.1524)
				(type default)
			)
			(layer "B.SilkS")
		)
		(fp_line
			(start 0.7874 -0.4064)
			(end -0.7874 -0.4064)
			(stroke
				(width 0.1524)
				(type default)
			)
			(layer "B.SilkS")
		)
		(fp_line
			(start 0.7874 0.4064)
			(end 0.7874 -0.4064)
			(stroke
				(width 0.1524)
				(type default)
			)
			(layer "B.SilkS")
		)
		(fp_line
			(start -0.67945 -0.3048)
			(end -0.67945 0.3048)
			(stroke
				(width 0.1)
				(type default)
			)
			(layer "B.Fab")
		)
		(fp_line
			(start -0.67945 0.3048)
			(end -0.120396 0.3048)
			(stroke
				(width 0.1)
				(type default)
			)
			(layer "B.Fab")
		)
		(fp_line
			(start -0.12065 -0.3048)
			(end -0.67945 -0.3048)
			(stroke
				(width 0.1)
				(type default)
			)
			(layer "B.Fab")
		)
		(fp_line
			(start -0.12065 -0.2794)
			(end -0.12065 -0.3048)
			(stroke
				(width 0.1)
				(type default)
			)
			(layer "B.Fab")
		)
		(fp_line
			(start -0.120396 0.2794)
			(end 0.12065 0.2794)
			(stroke
				(width 0.1)
				(type default)
			)
			(layer "B.Fab")
		)
		(fp_line
			(start -0.120396 0.3048)
			(end -0.120396 0.2794)
			(stroke
				(width 0.1)
				(type default)
			)
			(layer "B.Fab")
		)
		(fp_line
			(start 0.12065 -0.305054)
			(end 0.12065 -0.2794)
			(stroke
				(width 0.1)
				(type default)
			)
			(layer "B.Fab")
		)
		(fp_line
			(start 0.12065 -0.2794)
			(end -0.12065 -0.2794)
			(stroke
				(width 0.1)
				(type default)
			)
			(layer "B.Fab")
		)
		(fp_line
			(start 0.12065 0.2794)
			(end 0.12065 0.3048)
			(stroke
				(width 0.1)
				(type default)
			)
			(layer "B.Fab")
		)
		(fp_line
			(start 0.12065 0.3048)
			(end 0.67945 0.3048)
			(stroke
				(width 0.1)
				(type default)
			)
			(layer "B.Fab")
		)
		(fp_line
			(start 0.67945 -0.305054)
			(end 0.12065 -0.305054)
			(stroke
				(width 0.1)
				(type default)
			)
			(layer "B.Fab")
		)
		(fp_line
			(start 0.67945 0.3048)
			(end 0.67945 -0.305054)
			(stroke
				(width 0.1)
				(type default)
			)
			(layer "B.Fab")
		)
		(pad "1" smd circle
			(at 0.40005 0 180)
			(size 0 0)
			(layers "B.Cu" "B.Mask" "B.Paste")
			(net "FM_NCSI_OCP_SFF_R_OE")
		)
		(pad "2" smd circle
			(at -0.40005 0 180)
			(size 0 0)
			(layers "B.Cu" "B.Mask" "B.Paste")
			(net "FM_PLD_OCP_SFF_PWR_GOOD_R")
		)
	)
	(footprint ""
		(layer "B.Cu")
		(at 60.591192 -390.560052 90)
		(property "Reference" "C241"
			(at 0 0 90)
			(layer "B.SilkS")
			(hide yes)
			(effects
				(font
					(size 1.27 1.27)
				)
				(justify mirror)
			)
		)
		(property "Value" ""
			(at 0 0 90)
			(layer "B.Fab")
			(effects
				(font
					(size 1.27 1.27)
				)
				(justify mirror)
			)
		)
		(duplicate_pad_numbers_are_jumpers no)
		(fp_line
			(start 0.7874 -0.4064)
			(end -0.7874 -0.4064)
			(stroke
				(width 0.1524)
				(type default)
			)
			(layer "B.SilkS")
		)
		(fp_line
			(start -0.7874 -0.4064)
			(end -0.7874 0.4064)
			(stroke
				(width 0.1524)
				(type default)
			)
			(layer "B.SilkS")
		)
		(fp_line
			(start 0.7874 0.4064)
			(end 0.7874 -0.4064)
			(stroke
				(width 0.1524)
				(type default)
			)
			(layer "B.SilkS")
		)
		(fp_line
			(start -0.7874 0.4064)
			(end 0.7874 0.4064)
			(stroke
				(width 0.1524)
				(type default)
			)
			(layer "B.SilkS")
		)
		(fp_line
			(start 0.67945 -0.305054)
			(end 0.12065 -0.305054)
			(stroke
				(width 0.1)
				(type default)
			)
			(layer "B.Fab")
		)
		(fp_line
			(start 0.12065 -0.305054)
			(end 0.12065 -0.2794)
			(stroke
				(width 0.1)
				(type default)
			)
			(layer "B.Fab")
		)
		(fp_line
			(start -0.12065 -0.3048)
			(end -0.67945 -0.3048)
			(stroke
				(width 0.1)
				(type default)
			)
			(layer "B.Fab")
		)
		(fp_line
			(start -0.67945 -0.3048)
			(end -0.67945 0.3048)
			(stroke
				(width 0.1)
				(type default)
			)
			(layer "B.Fab")
		)
		(fp_line
			(start 0.12065 -0.2794)
			(end -0.12065 -0.2794)
			(stroke
				(width 0.1)
				(type default)
			)
			(layer "B.Fab")
		)
		(fp_line
			(start -0.12065 -0.2794)
			(end -0.12065 -0.3048)
			(stroke
				(width 0.1)
				(type default)
			)
			(layer "B.Fab")
		)
		(fp_line
			(start 0.12065 0.2794)
			(end 0.12065 0.3048)
			(stroke
				(width 0.1)
				(type default)
			)
			(layer "B.Fab")
		)
		(fp_line
			(start -0.120396 0.2794)
			(end 0.12065 0.2794)
			(stroke
				(width 0.1)
				(type default)
			)
			(layer "B.Fab")
		)
		(fp_line
			(start 0.67945 0.3048)
			(end 0.67945 -0.305054)
			(stroke
				(width 0.1)
				(type default)
			)
			(layer "B.Fab")
		)
		(fp_line
			(start 0.12065 0.3048)
			(end 0.67945 0.3048)
			(stroke
				(width 0.1)
				(type default)
			)
			(layer "B.Fab")
		)
		(fp_line
			(start -0.120396 0.3048)
			(end -0.120396 0.2794)
			(stroke
				(width 0.1)
				(type default)
			)
			(layer "B.Fab")
		)
		(fp_line
			(start -0.67945 0.3048)
			(end -0.120396 0.3048)
			(stroke
				(width 0.1)
				(type default)
			)
			(layer "B.Fab")
		)
		(pad "1" smd circle
			(at 0.40005 0 270)
			(size 0 0)
			(layers "B.Cu" "B.Mask" "B.Paste")
			(net "P0V9_CPU1_RT0_2A")
		)
		(pad "2" smd circle
			(at -0.40005 0 270)
			(size 0 0)
			(layers "B.Cu" "B.Mask" "B.Paste")
			(net "GND")
		)
	)
	(footprint ""
		(layer "B.Cu")
		(at 122.468386 -261.04723)
		(property "Reference" "C3917"
			(at 0 0 0)
			(layer "B.SilkS")
			(hide yes)
			(effects
				(font
					(size 1.27 1.27)
				)
				(justify mirror)
			)
		)
		(property "Value" ""
			(at 0 0 0)
			(layer "B.Fab")
			(effects
				(font
					(size 1.27 1.27)
				)
				(justify mirror)
			)
		)
		(duplicate_pad_numbers_are_jumpers no)
		(fp_line
			(start -0.7874 -0.4064)
			(end -0.7874 0.4064)
			(stroke
				(width 0.1524)
				(type default)
			)
			(layer "B.SilkS")
		)
		(fp_line
			(start -0.7874 0.4064)
			(end 0.7874 0.4064)
			(stroke
				(width 0.1524)
				(type default)
			)
			(layer "B.SilkS")
		)
		(fp_line
			(start 0.7874 -0.4064)
			(end -0.7874 -0.4064)
			(stroke
				(width 0.1524)
				(type default)
			)
			(layer "B.SilkS")
		)
		(fp_line
			(start 0.7874 0.4064)
			(end 0.7874 -0.4064)
			(stroke
				(width 0.1524)
				(type default)
			)
			(layer "B.SilkS")
		)
		(fp_line
			(start -0.67945 -0.3048)
			(end -0.67945 0.3048)
			(stroke
				(width 0.1)
				(type default)
			)
			(layer "B.Fab")
		)
		(fp_line
			(start -0.67945 0.3048)
			(end -0.120396 0.3048)
			(stroke
				(width 0.1)
				(type default)
			)
			(layer "B.Fab")
		)
		(fp_line
			(start -0.12065 -0.3048)
			(end -0.67945 -0.3048)
			(stroke
				(width 0.1)
				(type default)
			)
			(layer "B.Fab")
		)
		(fp_line
			(start -0.12065 -0.2794)
			(end -0.12065 -0.3048)
			(stroke
				(width 0.1)
				(type default)
			)
			(layer "B.Fab")
		)
		(fp_line
			(start -0.120396 0.2794)
			(end 0.12065 0.2794)
			(stroke
				(width 0.1)
				(type default)
			)
			(layer "B.Fab")
		)
		(fp_line
			(start -0.120396 0.3048)
			(end -0.120396 0.2794)
			(stroke
				(width 0.1)
				(type default)
			)
			(layer "B.Fab")
		)
		(fp_line
			(start 0.12065 -0.305054)
			(end 0.12065 -0.2794)
			(stroke
				(width 0.1)
				(type default)
			)
			(layer "B.Fab")
		)
		(fp_line
			(start 0.12065 -0.2794)
			(end -0.12065 -0.2794)
			(stroke
				(width 0.1)
				(type default)
			)
			(layer "B.Fab")
		)
		(fp_line
			(start 0.12065 0.2794)
			(end 0.12065 0.3048)
			(stroke
				(width 0.1)
				(type default)
			)
			(layer "B.Fab")
		)
		(fp_line
			(start 0.12065 0.3048)
			(end 0.67945 0.3048)
			(stroke
				(width 0.1)
				(type default)
			)
			(layer "B.Fab")
		)
		(fp_line
			(start 0.67945 -0.305054)
			(end 0.12065 -0.305054)
			(stroke
				(width 0.1)
				(type default)
			)
			(layer "B.Fab")
		)
		(fp_line
			(start 0.67945 0.3048)
			(end 0.67945 -0.305054)
			(stroke
				(width 0.1)
				(type default)
			)
			(layer "B.Fab")
		)
		(pad "1" smd circle
			(at 0.40005 0 180)
			(size 0 0)
			(layers "B.Cu" "B.Mask" "B.Paste")
			(net "PVDDCR_SOC_P1")
		)
		(pad "2" smd circle
			(at -0.40005 0 180)
			(size 0 0)
			(layers "B.Cu" "B.Mask" "B.Paste")
			(net "GND")
		)
	)
	(footprint ""
		(layer "B.Cu")
		(at 67.201034 -199.336152)
		(property "Reference" "R553"
			(at 0 0 0)
			(layer "B.SilkS")
			(hide yes)
			(effects
				(font
					(size 1.27 1.27)
				)
				(justify mirror)
			)
		)
		(property "Value" ""
			(at 0 0 0)
			(layer "B.Fab")
			(effects
				(font
					(size 1.27 1.27)
				)
				(justify mirror)
			)
		)
		(duplicate_pad_numbers_are_jumpers no)
		(fp_line
			(start -0.7874 -0.4064)
			(end -0.7874 0.4064)
			(stroke
				(width 0.1524)
				(type default)
			)
			(layer "B.SilkS")
		)
		(fp_line
			(start -0.7874 0.4064)
			(end 0.7874 0.4064)
			(stroke
				(width 0.1524)
				(type default)
			)
			(layer "B.SilkS")
		)
		(fp_line
			(start 0.7874 -0.4064)
			(end -0.7874 -0.4064)
			(stroke
				(width 0.1524)
				(type default)
			)
			(layer "B.SilkS")
		)
		(fp_line
			(start 0.7874 0.4064)
			(end 0.7874 -0.4064)
			(stroke
				(width 0.1524)
				(type default)
			)
			(layer "B.SilkS")
		)
		(fp_line
			(start -0.67945 -0.3048)
			(end -0.67945 0.3048)
			(stroke
				(width 0.1)
				(type default)
			)
			(layer "B.Fab")
		)
		(fp_line
			(start -0.67945 0.3048)
			(end -0.120396 0.3048)
			(stroke
				(width 0.1)
				(type default)
			)
			(layer "B.Fab")
		)
		(fp_line
			(start -0.12065 -0.3048)
			(end -0.67945 -0.3048)
			(stroke
				(width 0.1)
				(type default)
			)
			(layer "B.Fab")
		)
		(fp_line
			(start -0.12065 -0.2794)
			(end -0.12065 -0.3048)
			(stroke
				(width 0.1)
				(type default)
			)
			(layer "B.Fab")
		)
		(fp_line
			(start -0.120396 0.2794)
			(end 0.12065 0.2794)
			(stroke
				(width 0.1)
				(type default)
			)
			(layer "B.Fab")
		)
		(fp_line
			(start -0.120396 0.3048)
			(end -0.120396 0.2794)
			(stroke
				(width 0.1)
				(type default)
			)
			(layer "B.Fab")
		)
		(fp_line
			(start 0.12065 -0.305054)
			(end 0.12065 -0.2794)
			(stroke
				(width 0.1)
				(type default)
			)
			(layer "B.Fab")
		)
		(fp_line
			(start 0.12065 -0.2794)
			(end -0.12065 -0.2794)
			(stroke
				(width 0.1)
				(type default)
			)
			(layer "B.Fab")
		)
		(fp_line
			(start 0.12065 0.2794)
			(end 0.12065 0.3048)
			(stroke
				(width 0.1)
				(type default)
			)
			(layer "B.Fab")
		)
		(fp_line
			(start 0.12065 0.3048)
			(end 0.67945 0.3048)
			(stroke
				(width 0.1)
				(type default)
			)
			(layer "B.Fab")
		)
		(fp_line
			(start 0.67945 -0.305054)
			(end 0.12065 -0.305054)
			(stroke
				(width 0.1)
				(type default)
			)
			(layer "B.Fab")
		)
		(fp_line
			(start 0.67945 0.3048)
			(end 0.67945 -0.305054)
			(stroke
				(width 0.1)
				(type default)
			)
			(layer "B.Fab")
		)
		(pad "1" smd circle
			(at 0.40005 0 180)
			(size 0 0)
			(layers "B.Cu" "B.Mask" "B.Paste")
			(net "CPU1_NV_SAVE_N")
		)
		(pad "2" smd circle
			(at -0.40005 0 180)
			(size 0 0)
			(layers "B.Cu" "B.Mask" "B.Paste")
			(net "PVDD18_S5_P1")
		)
	)
	(footprint ""
		(layer "B.Cu")
		(at 92.185744 -408.517344 90)
		(property "Reference" "C6690"
			(at 0 0 90)
			(layer "B.SilkS")
			(hide yes)
			(effects
				(font
					(size 1.27 1.27)
				)
				(justify mirror)
			)
		)
		(property "Value" ""
			(at 0 0 90)
			(layer "B.Fab")
			(effects
				(font
					(size 1.27 1.27)
				)
				(justify mirror)
			)
		)
		(duplicate_pad_numbers_are_jumpers no)
		(fp_line
			(start 0.299974 -0.150114)
			(end -0.299974 -0.150114)
			(stroke
				(width 0.1)
				(type default)
			)
			(layer "B.Fab")
		)
		(fp_line
			(start -0.299974 -0.150114)
			(end -0.299974 0.150114)
			(stroke
				(width 0.1)
				(type default)
			)
			(layer "B.Fab")
		)
		(fp_line
			(start 0.299974 0.150114)
			(end 0.299974 -0.150114)
			(stroke
				(width 0.1)
				(type default)
			)
			(layer "B.Fab")
		)
		(fp_line
			(start -0.299974 0.150114)
			(end 0.299974 0.150114)
			(stroke
				(width 0.1)
				(type default)
			)
			(layer "B.Fab")
		)
		(pad "1" smd rect
			(at 0.2667 0 270)
			(size 0.3048 0.381)
			(layers "B.Cu" "B.Mask" "B.Paste")
			(net "P5E_CPU1_P1_TX_BUF_C_DN<14>")
		)
		(pad "2" smd rect
			(at -0.2667 0 270)
			(size 0.3048 0.381)
			(layers "B.Cu" "B.Mask" "B.Paste")
			(net "P5E_CPU1_P1_TX_BUF_DN<14>")
		)
	)
	(footprint ""
		(layer "B.Cu")
		(at 340.718902 -398.942052 90)
		(property "Reference" "C630"
			(at 0 0 90)
			(layer "B.SilkS")
			(hide yes)
			(effects
				(font
					(size 1.27 1.27)
				)
				(justify mirror)
			)
		)
		(property "Value" ""
			(at 0 0 90)
			(layer "B.Fab")
			(effects
				(font
					(size 1.27 1.27)
				)
				(justify mirror)
			)
		)
		(duplicate_pad_numbers_are_jumpers no)
		(fp_line
			(start 0.7874 -0.4064)
			(end -0.7874 -0.4064)
			(stroke
				(width 0.1524)
				(type default)
			)
			(layer "B.SilkS")
		)
		(fp_line
			(start -0.7874 -0.4064)
			(end -0.7874 0.4064)
			(stroke
				(width 0.1524)
				(type default)
			)
			(layer "B.SilkS")
		)
		(fp_line
			(start 0.7874 0.4064)
			(end 0.7874 -0.4064)
			(stroke
				(width 0.1524)
				(type default)
			)
			(layer "B.SilkS")
		)
		(fp_line
			(start -0.7874 0.4064)
			(end 0.7874 0.4064)
			(stroke
				(width 0.1524)
				(type default)
			)
			(layer "B.SilkS")
		)
		(fp_line
			(start 0.67945 -0.305054)
			(end 0.12065 -0.305054)
			(stroke
				(width 0.1)
				(type default)
			)
			(layer "B.Fab")
		)
		(fp_line
			(start 0.12065 -0.305054)
			(end 0.12065 -0.2794)
			(stroke
				(width 0.1)
				(type default)
			)
			(layer "B.Fab")
		)
		(fp_line
			(start -0.12065 -0.3048)
			(end -0.67945 -0.3048)
			(stroke
				(width 0.1)
				(type default)
			)
			(layer "B.Fab")
		)
		(fp_line
			(start -0.67945 -0.3048)
			(end -0.67945 0.3048)
			(stroke
				(width 0.1)
				(type default)
			)
			(layer "B.Fab")
		)
		(fp_line
			(start 0.12065 -0.2794)
			(end -0.12065 -0.2794)
			(stroke
				(width 0.1)
				(type default)
			)
			(layer "B.Fab")
		)
		(fp_line
			(start -0.12065 -0.2794)
			(end -0.12065 -0.3048)
			(stroke
				(width 0.1)
				(type default)
			)
			(layer "B.Fab")
		)
		(fp_line
			(start 0.12065 0.2794)
			(end 0.12065 0.3048)
			(stroke
				(width 0.1)
				(type default)
			)
			(layer "B.Fab")
		)
		(fp_line
			(start -0.120396 0.2794)
			(end 0.12065 0.2794)
			(stroke
				(width 0.1)
				(type default)
			)
			(layer "B.Fab")
		)
		(fp_line
			(start 0.67945 0.3048)
			(end 0.67945 -0.305054)
			(stroke
				(width 0.1)
				(type default)
			)
			(layer "B.Fab")
		)
		(fp_line
			(start 0.12065 0.3048)
			(end 0.67945 0.3048)
			(stroke
				(width 0.1)
				(type default)
			)
			(layer "B.Fab")
		)
		(fp_line
			(start -0.120396 0.3048)
			(end -0.120396 0.2794)
			(stroke
				(width 0.1)
				(type default)
			)
			(layer "B.Fab")
		)
		(fp_line
			(start -0.67945 0.3048)
			(end -0.120396 0.3048)
			(stroke
				(width 0.1)
				(type default)
			)
			(layer "B.Fab")
		)
		(pad "1" smd circle
			(at 0.40005 0 270)
			(size 0 0)
			(layers "B.Cu" "B.Mask" "B.Paste")
			(net "P0V9_CPU0_RT1_2A")
		)
		(pad "2" smd circle
			(at -0.40005 0 270)
			(size 0 0)
			(layers "B.Cu" "B.Mask" "B.Paste")
			(net "GND")
		)
	)
	(footprint ""
		(layer "B.Cu")
		(at 180.608986 -352.354642 -90)
		(property "Reference" "PR326"
			(at 0 0 90)
			(layer "B.SilkS")
			(hide yes)
			(effects
				(font
					(size 1.27 1.27)
				)
				(justify mirror)
			)
		)
		(property "Value" ""
			(at 0 0 90)
			(layer "B.Fab")
			(effects
				(font
					(size 1.27 1.27)
				)
				(justify mirror)
			)
		)
		(duplicate_pad_numbers_are_jumpers no)
		(fp_line
			(start -0.7874 0.4064)
			(end 0.7874 0.4064)
			(stroke
				(width 0.1524)
				(type default)
			)
			(layer "B.SilkS")
		)
		(fp_line
			(start 0.7874 0.4064)
			(end 0.7874 -0.4064)
			(stroke
				(width 0.1524)
				(type default)
			)
			(layer "B.SilkS")
		)
		(fp_line
			(start -0.7874 -0.4064)
			(end -0.7874 0.4064)
			(stroke
				(width 0.1524)
				(type default)
			)
			(layer "B.SilkS")
		)
		(fp_line
			(start 0.7874 -0.4064)
			(end -0.7874 -0.4064)
			(stroke
				(width 0.1524)
				(type default)
			)
			(layer "B.SilkS")
		)
		(fp_line
			(start -0.67945 0.3048)
			(end -0.120396 0.3048)
			(stroke
				(width 0.1)
				(type default)
			)
			(layer "B.Fab")
		)
		(fp_line
			(start -0.120396 0.3048)
			(end -0.120396 0.2794)
			(stroke
				(width 0.1)
				(type default)
			)
			(layer "B.Fab")
		)
		(fp_line
			(start 0.12065 0.3048)
			(end 0.67945 0.3048)
			(stroke
				(width 0.1)
				(type default)
			)
			(layer "B.Fab")
		)
		(fp_line
			(start 0.67945 0.3048)
			(end 0.67945 -0.305054)
			(stroke
				(width 0.1)
				(type default)
			)
			(layer "B.Fab")
		)
		(fp_line
			(start -0.120396 0.2794)
			(end 0.12065 0.2794)
			(stroke
				(width 0.1)
				(type default)
			)
			(layer "B.Fab")
		)
		(fp_line
			(start 0.12065 0.2794)
			(end 0.12065 0.3048)
			(stroke
				(width 0.1)
				(type default)
			)
			(layer "B.Fab")
		)
		(fp_line
			(start -0.12065 -0.2794)
			(end -0.12065 -0.3048)
			(stroke
				(width 0.1)
				(type default)
			)
			(layer "B.Fab")
		)
		(fp_line
			(start 0.12065 -0.2794)
			(end -0.12065 -0.2794)
			(stroke
				(width 0.1)
				(type default)
			)
			(layer "B.Fab")
		)
		(fp_line
			(start -0.67945 -0.3048)
			(end -0.67945 0.3048)
			(stroke
				(width 0.1)
				(type default)
			)
			(layer "B.Fab")
		)
		(fp_line
			(start -0.12065 -0.3048)
			(end -0.67945 -0.3048)
			(stroke
				(width 0.1)
				(type default)
			)
			(layer "B.Fab")
		)
		(fp_line
			(start 0.12065 -0.305054)
			(end 0.12065 -0.2794)
			(stroke
				(width 0.1)
				(type default)
			)
			(layer "B.Fab")
		)
		(fp_line
			(start 0.67945 -0.305054)
			(end 0.12065 -0.305054)
			(stroke
				(width 0.1)
				(type default)
			)
			(layer "B.Fab")
		)
		(pad "1" smd circle
			(at 0.40005 0 90)
			(size 0 0)
			(layers "B.Cu" "B.Mask" "B.Paste")
			(net "PVDD11_S3_P1_PVCC")
		)
		(pad "2" smd circle
			(at -0.40005 0 90)
			(size 0 0)
			(layers "B.Cu" "B.Mask" "B.Paste")
			(net "PVDD11_S3_P1_VCC1")
		)
	)
)
